(kicad_pcb
	(version 20260206)
	(generator "pcbnew")
	(generator_version "10.0")
	(general
		(thickness 1.6)
		(legacy_teardrops no)
	)
	(paper "A4")
	(title_block
		(title "01162023_DA0F0TEBIF0_F0T_Expander_BD_F_brd_V02_OCP.brd")
		(comment 1 "Grand Teton / footprints 5985-5990 of 9728")
	)
	(layers
		(0 "F.Cu" signal "TOP")
		(4 "In1.Cu" signal "GND")
		(6 "In2.Cu" signal "VCC")
		(8 "In3.Cu" signal "VCC1")
		(10 "In4.Cu" signal "GND1")
		(12 "In5.Cu" signal "IN1")
		(14 "In6.Cu" signal "GND2")
		(16 "In7.Cu" signal "IN2")
		(18 "In8.Cu" signal "GND3")
		(20 "In9.Cu" signal "IN3")
		(22 "In10.Cu" signal "GND4")
		(24 "In11.Cu" signal "IN4")
		(26 "In12.Cu" signal "GND5")
		(28 "In13.Cu" signal "IN5")
		(30 "In14.Cu" signal "GND6")
		(32 "In15.Cu" signal "IN6")
		(34 "In16.Cu" signal "GND7")
		(2 "B.Cu" signal "BOTTOM")
		(9 "F.Adhes" user "F.Adhesive")
		(11 "B.Adhes" user "B.Adhesive")
		(13 "F.Paste" user "Package Geometry/Pastemask Top")
		(15 "B.Paste" user "Package Geometry/Pastemask Bottom")
		(5 "F.SilkS" user "Ref Des/Silkscreen Top")
		(7 "B.SilkS" user "Ref Des/Silkscreen Bottom")
		(1 "F.Mask" user "Board Geometry/Soldermask Top")
		(3 "B.Mask" user "Board Geometry/Soldermask Bottom")
		(17 "Dwgs.User" user "User.Drawings")
		(19 "Cmts.User" user "User.Comments")
		(21 "Eco1.User" user "User.Eco1")
		(23 "Eco2.User" user "User.Eco2")
		(25 "Edge.Cuts" user "Board Geometry/Outline")
		(27 "Margin" user)
		(31 "F.CrtYd" user "Package Geometry/Place Bound Top")
		(29 "B.CrtYd" user "Package Geometry/Place Bound Bottom")
		(35 "F.Fab" user "Ref Des/Assembly Top")
		(33 "B.Fab" user "Ref Des/Assembly Bottom")
	)
	(footprint ""
		(layer "F.Cu")
		(at 142.368016 -52.035456 180)
		(property "Reference" "R862"
			(at 0 0 180)
			(layer "F.SilkS")
			(hide yes)
			(effects
				(font
					(size 1.27 1.27)
				)
			)
		)
		(property "Value" ""
			(at 0 0 180)
			(layer "F.Fab")
			(effects
				(font
					(size 1.27 1.27)
				)
			)
		)
		(duplicate_pad_numbers_are_jumpers no)
		(fp_line
			(start 0.7874 0.4064)
			(end -0.7874 0.4064)
			(stroke
				(width 0.1524)
				(type default)
			)
			(layer "F.SilkS")
		)
		(fp_line
			(start 0.7874 -0.4064)
			(end 0.7874 0.4064)
			(stroke
				(width 0.1524)
				(type default)
			)
			(layer "F.SilkS")
		)
		(fp_line
			(start -0.7874 0.4064)
			(end -0.7874 -0.4064)
			(stroke
				(width 0.1524)
				(type default)
			)
			(layer "F.SilkS")
		)
		(fp_line
			(start -0.7874 -0.4064)
			(end 0.7874 -0.4064)
			(stroke
				(width 0.1524)
				(type default)
			)
			(layer "F.SilkS")
		)
		(fp_line
			(start 0.67945 0.3048)
			(end 0.120396 0.3048)
			(stroke
				(width 0.1)
				(type default)
			)
			(layer "F.Fab")
		)
		(fp_line
			(start 0.67945 -0.3048)
			(end 0.67945 0.3048)
			(stroke
				(width 0.1)
				(type default)
			)
			(layer "F.Fab")
		)
		(fp_line
			(start 0.12065 -0.2794)
			(end 0.12065 -0.3048)
			(stroke
				(width 0.1)
				(type default)
			)
			(layer "F.Fab")
		)
		(fp_line
			(start 0.12065 -0.3048)
			(end 0.67945 -0.3048)
			(stroke
				(width 0.1)
				(type default)
			)
			(layer "F.Fab")
		)
		(fp_line
			(start 0.120396 0.3048)
			(end 0.120396 0.2794)
			(stroke
				(width 0.1)
				(type default)
			)
			(layer "F.Fab")
		)
		(fp_line
			(start 0.120396 0.2794)
			(end -0.12065 0.2794)
			(stroke
				(width 0.1)
				(type default)
			)
			(layer "F.Fab")
		)
		(fp_line
			(start -0.12065 0.3048)
			(end -0.67945 0.3048)
			(stroke
				(width 0.1)
				(type default)
			)
			(layer "F.Fab")
		)
		(fp_line
			(start -0.12065 0.2794)
			(end -0.12065 0.3048)
			(stroke
				(width 0.1)
				(type default)
			)
			(layer "F.Fab")
		)
		(fp_line
			(start -0.12065 -0.2794)
			(end 0.12065 -0.2794)
			(stroke
				(width 0.1)
				(type default)
			)
			(layer "F.Fab")
		)
		(fp_line
			(start -0.12065 -0.305054)
			(end -0.12065 -0.2794)
			(stroke
				(width 0.1)
				(type default)
			)
			(layer "F.Fab")
		)
		(fp_line
			(start -0.67945 0.3048)
			(end -0.67945 -0.305054)
			(stroke
				(width 0.1)
				(type default)
			)
			(layer "F.Fab")
		)
		(fp_line
			(start -0.67945 -0.305054)
			(end -0.12065 -0.305054)
			(stroke
				(width 0.1)
				(type default)
			)
			(layer "F.Fab")
		)
		(pad "1" smd circle
			(at -0.40005 0 180)
			(size 0 0)
			(layers "F.Cu" "F.Mask" "F.Paste")
			(net "P3V3_AUX")
		)
		(pad "2" smd circle
			(at 0.40005 0 180)
			(size 0 0)
			(layers "F.Cu" "F.Mask" "F.Paste")
			(net "PWRGD_P12V_SSD4")
		)
	)
	(footprint ""
		(layer "F.Cu")
		(at 96.620076 -15.649956 180)
		(property "Reference" "H118"
			(at -3.792474 -2.39141 0)
			(unlocked yes)
			(layer "B.SilkS")
			(effects
				(font
					(size 0.7874 0.5842)
					(thickness 0.1524)
				)
				(justify left mirror)
			)
		)
		(property "Value" ""
			(at 0 0 180)
			(layer "F.Fab")
			(effects
				(font
					(size 1.27 1.27)
				)
			)
		)
		(duplicate_pad_numbers_are_jumpers no)
		(pad "1" thru_hole rect
			(at 0 0 180)
			(size 4.2164 5.0038)
			(drill 2.0066
				(offset 0.099822 0)
			)
			(layers "*.Cu" "*.Mask")
			(remove_unused_layers no)
			(net "Net_8545")
			(clearance -0.8509)
			(padstack
				(mode front_inner_back)
				(layer "Inner"
					(shape circle)
					(size 4.0132 4.0132)
					(clearance -0.7493)
				)
				(layer "B.Cu"
					(shape circle)
					(size 4.0132 4.0132)
					(clearance -0.7493)
				)
			)
		)
	)
	(footprint ""
		(layer "F.Cu")
		(at 259.326126 -37.929566 90)
		(property "Reference" "R5570"
			(at 0 0 90)
			(layer "F.SilkS")
			(hide yes)
			(effects
				(font
					(size 1.27 1.27)
				)
			)
		)
		(property "Value" ""
			(at 0 0 90)
			(layer "F.Fab")
			(effects
				(font
					(size 1.27 1.27)
				)
			)
		)
		(duplicate_pad_numbers_are_jumpers no)
		(fp_line
			(start 0.7874 -0.4064)
			(end 0.7874 0.4064)
			(stroke
				(width 0.1524)
				(type default)
			)
			(layer "F.SilkS")
		)
		(fp_line
			(start -0.7874 -0.4064)
			(end 0.7874 -0.4064)
			(stroke
				(width 0.1524)
				(type default)
			)
			(layer "F.SilkS")
		)
		(fp_line
			(start 0.7874 0.4064)
			(end -0.7874 0.4064)
			(stroke
				(width 0.1524)
				(type default)
			)
			(layer "F.SilkS")
		)
		(fp_line
			(start -0.7874 0.4064)
			(end -0.7874 -0.4064)
			(stroke
				(width 0.1524)
				(type default)
			)
			(layer "F.SilkS")
		)
		(fp_line
			(start -0.12065 -0.305054)
			(end -0.12065 -0.2794)
			(stroke
				(width 0.1)
				(type default)
			)
			(layer "F.Fab")
		)
		(fp_line
			(start -0.67945 -0.305054)
			(end -0.12065 -0.305054)
			(stroke
				(width 0.1)
				(type default)
			)
			(layer "F.Fab")
		)
		(fp_line
			(start 0.67945 -0.3048)
			(end 0.67945 0.3048)
			(stroke
				(width 0.1)
				(type default)
			)
			(layer "F.Fab")
		)
		(fp_line
			(start 0.12065 -0.3048)
			(end 0.67945 -0.3048)
			(stroke
				(width 0.1)
				(type default)
			)
			(layer "F.Fab")
		)
		(fp_line
			(start 0.12065 -0.2794)
			(end 0.12065 -0.3048)
			(stroke
				(width 0.1)
				(type default)
			)
			(layer "F.Fab")
		)
		(fp_line
			(start -0.12065 -0.2794)
			(end 0.12065 -0.2794)
			(stroke
				(width 0.1)
				(type default)
			)
			(layer "F.Fab")
		)
		(fp_line
			(start 0.120396 0.2794)
			(end -0.12065 0.2794)
			(stroke
				(width 0.1)
				(type default)
			)
			(layer "F.Fab")
		)
		(fp_line
			(start -0.12065 0.2794)
			(end -0.12065 0.3048)
			(stroke
				(width 0.1)
				(type default)
			)
			(layer "F.Fab")
		)
		(fp_line
			(start 0.67945 0.3048)
			(end 0.120396 0.3048)
			(stroke
				(width 0.1)
				(type default)
			)
			(layer "F.Fab")
		)
		(fp_line
			(start 0.120396 0.3048)
			(end 0.120396 0.2794)
			(stroke
				(width 0.1)
				(type default)
			)
			(layer "F.Fab")
		)
		(fp_line
			(start -0.12065 0.3048)
			(end -0.67945 0.3048)
			(stroke
				(width 0.1)
				(type default)
			)
			(layer "F.Fab")
		)
		(fp_line
			(start -0.67945 0.3048)
			(end -0.67945 -0.305054)
			(stroke
				(width 0.1)
				(type default)
			)
			(layer "F.Fab")
		)
		(pad "1" smd circle
			(at -0.40005 0 90)
			(size 0 0)
			(layers "F.Cu" "F.Mask" "F.Paste")
			(net "SSD9_AUX_P3V3_EN_R")
		)
		(pad "2" smd circle
			(at 0.40005 0 90)
			(size 0 0)
			(layers "F.Cu" "F.Mask" "F.Paste")
			(net "SSD9_AUX_P3V3_EN")
		)
	)
	(footprint ""
		(layer "F.Cu")
		(at 262.353298 -297.791632)
		(property "Reference" "L120"
			(at 0 0 0)
			(layer "F.SilkS")
			(hide yes)
			(effects
				(font
					(size 1.27 1.27)
				)
			)
		)
		(property "Value" ""
			(at 0 0 0)
			(layer "F.Fab")
			(effects
				(font
					(size 1.27 1.27)
				)
			)
		)
		(duplicate_pad_numbers_are_jumpers no)
		(fp_line
			(start -1.63576 -0.8128)
			(end -1.63576 0.8128)
			(stroke
				(width 0.1524)
				(type default)
			)
			(layer "F.SilkS")
		)
		(fp_line
			(start -1.63576 -0.8128)
			(end 1.63576 -0.8128)
			(stroke
				(width 0.1524)
				(type default)
			)
			(layer "F.SilkS")
		)
		(fp_line
			(start 1.63576 -0.8128)
			(end 1.63576 0.8128)
			(stroke
				(width 0.1524)
				(type default)
			)
			(layer "F.SilkS")
		)
		(fp_line
			(start 1.63576 0.8128)
			(end -1.63576 0.8128)
			(stroke
				(width 0.1524)
				(type default)
			)
			(layer "F.SilkS")
		)
		(fp_line
			(start -1.56083 -0.738632)
			(end -1.56083 0.7366)
			(stroke
				(width 0.1)
				(type default)
			)
			(layer "F.Fab")
		)
		(fp_line
			(start -1.56083 0.7366)
			(end -1.524 0.7366)
			(stroke
				(width 0.1)
				(type default)
			)
			(layer "F.Fab")
		)
		(fp_line
			(start -1.524 0.7366)
			(end 1.524 0.7366)
			(stroke
				(width 0.1)
				(type default)
			)
			(layer "F.Fab")
		)
		(fp_line
			(start 1.524 0.7366)
			(end 1.560576 0.7366)
			(stroke
				(width 0.1)
				(type default)
			)
			(layer "F.Fab")
		)
		(fp_line
			(start 1.560576 -0.738632)
			(end -1.56083 -0.738632)
			(stroke
				(width 0.1)
				(type default)
			)
			(layer "F.Fab")
		)
		(fp_line
			(start 1.560576 0.7366)
			(end 1.560576 -0.738632)
			(stroke
				(width 0.1)
				(type default)
			)
			(layer "F.Fab")
		)
		(pad "1" smd rect
			(at -0.94996 0 180)
			(size 1.1176 1.3716)
			(layers "F.Cu" "F.Mask" "F.Paste")
			(net "P1V8_PLL0_PEX2")
		)
		(pad "2" smd rect
			(at 0.94996 0 180)
			(size 1.1176 1.3716)
			(layers "F.Cu" "F.Mask" "F.Paste")
			(net "PCEPLL0_VDDA18_PEX2")
		)
	)
	(footprint ""
		(layer "F.Cu")
		(at 358.41051 -124.963428 180)
		(property "Reference" "R4479"
			(at 0 0 180)
			(layer "F.SilkS")
			(hide yes)
			(effects
				(font
					(size 1.27 1.27)
				)
			)
		)
		(property "Value" ""
			(at 0 0 180)
			(layer "F.Fab")
			(effects
				(font
					(size 1.27 1.27)
				)
			)
		)
		(duplicate_pad_numbers_are_jumpers no)
		(fp_line
			(start 0.7874 0.4064)
			(end -0.7874 0.4064)
			(stroke
				(width 0.1524)
				(type default)
			)
			(layer "F.SilkS")
		)
		(fp_line
			(start 0.7874 -0.4064)
			(end 0.7874 0.4064)
			(stroke
				(width 0.1524)
				(type default)
			)
			(layer "F.SilkS")
		)
		(fp_line
			(start -0.7874 0.4064)
			(end -0.7874 -0.4064)
			(stroke
				(width 0.1524)
				(type default)
			)
			(layer "F.SilkS")
		)
		(fp_line
			(start -0.7874 -0.4064)
			(end 0.7874 -0.4064)
			(stroke
				(width 0.1524)
				(type default)
			)
			(layer "F.SilkS")
		)
		(fp_line
			(start 0.67945 0.3048)
			(end 0.120396 0.3048)
			(stroke
				(width 0.1)
				(type default)
			)
			(layer "F.Fab")
		)
		(fp_line
			(start 0.67945 -0.3048)
			(end 0.67945 0.3048)
			(stroke
				(width 0.1)
				(type default)
			)
			(layer "F.Fab")
		)
		(fp_line
			(start 0.12065 -0.2794)
			(end 0.12065 -0.3048)
			(stroke
				(width 0.1)
				(type default)
			)
			(layer "F.Fab")
		)
		(fp_line
			(start 0.12065 -0.3048)
			(end 0.67945 -0.3048)
			(stroke
				(width 0.1)
				(type default)
			)
			(layer "F.Fab")
		)
		(fp_line
			(start 0.120396 0.3048)
			(end 0.120396 0.2794)
			(stroke
				(width 0.1)
				(type default)
			)
			(layer "F.Fab")
		)
		(fp_line
			(start 0.120396 0.2794)
			(end -0.12065 0.2794)
			(stroke
				(width 0.1)
				(type default)
			)
			(layer "F.Fab")
		)
		(fp_line
			(start -0.12065 0.3048)
			(end -0.67945 0.3048)
			(stroke
				(width 0.1)
				(type default)
			)
			(layer "F.Fab")
		)
		(fp_line
			(start -0.12065 0.2794)
			(end -0.12065 0.3048)
			(stroke
				(width 0.1)
				(type default)
			)
			(layer "F.Fab")
		)
		(fp_line
			(start -0.12065 -0.2794)
			(end 0.12065 -0.2794)
			(stroke
				(width 0.1)
				(type default)
			)
			(layer "F.Fab")
		)
		(fp_line
			(start -0.12065 -0.305054)
			(end -0.12065 -0.2794)
			(stroke
				(width 0.1)
				(type default)
			)
			(layer "F.Fab")
		)
		(fp_line
			(start -0.67945 0.3048)
			(end -0.67945 -0.305054)
			(stroke
				(width 0.1)
				(type default)
			)
			(layer "F.Fab")
		)
		(fp_line
			(start -0.67945 -0.305054)
			(end -0.12065 -0.305054)
			(stroke
				(width 0.1)
				(type default)
			)
			(layer "F.Fab")
		)
		(pad "1" smd circle
			(at -0.40005 0 180)
			(size 0 0)
			(layers "F.Cu" "F.Mask" "F.Paste")
			(net "PWRGD_P3V3_NIC6")
		)
		(pad "2" smd circle
			(at 0.40005 0 180)
			(size 0 0)
			(layers "F.Cu" "F.Mask" "F.Paste")
			(net "PWRGD_P3V3_NIC6_R")
		)
	)
	(footprint ""
		(layer "F.Cu")
		(at 395.735556 -249.0216)
		(property "Reference" "J67"
			(at -1.4224 -4.562348 0)
			(unlocked yes)
			(layer "F.SilkS")
			(effects
				(font
					(size 0.7874 0.5842)
					(thickness 0.1524)
				)
				(justify left)
			)
		)
		(property "Value" ""
			(at 0 0 0)
			(layer "F.Fab")
			(effects
				(font
					(size 1.27 1.27)
				)
			)
		)
		(duplicate_pad_numbers_are_jumpers no)
		(fp_line
			(start -1.27 -3.81)
			(end 1.27 -3.81)
			(stroke
				(width 0.1524)
				(type default)
			)
			(layer "F.SilkS")
		)
		(fp_line
			(start -1.27 -0.7747)
			(end -1.27 -3.81)
			(stroke
				(width 0.1524)
				(type default)
			)
			(layer "F.SilkS")
		)
		(fp_line
			(start -1.27 3.81)
			(end -1.27 0.7747)
			(stroke
				(width 0.1524)
				(type default)
			)
			(layer "F.SilkS")
		)
		(fp_line
			(start 1.27 -3.81)
			(end 1.27 -3.3147)
			(stroke
				(width 0.1524)
				(type default)
			)
			(layer "F.SilkS")
		)
		(fp_line
			(start 1.27 -1.7653)
			(end 1.27 1.7653)
			(stroke
				(width 0.1524)
				(type default)
			)
			(layer "F.SilkS")
		)
		(fp_line
			(start 1.27 3.3147)
			(end 1.27 3.81)
			(stroke
				(width 0.1524)
				(type default)
			)
			(layer "F.SilkS")
		)
		(fp_line
			(start 1.27 3.81)
			(end -1.27 3.81)
			(stroke
				(width 0.1524)
				(type default)
			)
			(layer "F.SilkS")
		)
		(fp_poly
			(pts
				(xy 4.3942 -3.048) (xy 4.3942 -2.032) (xy 3.3782 -2.54)
			)
			(stroke
				(width 0)
				(type default)
			)
			(fill yes)
			(layer "F.SilkS")
		)
		(fp_line
			(start -1.27 -3.81)
			(end -1.27 3.81)
			(stroke
				(width 0.1)
				(type default)
			)
			(layer "F.Fab")
		)
		(fp_line
			(start -1.27 3.81)
			(end 1.27 3.81)
			(stroke
				(width 0.1)
				(type default)
			)
			(layer "F.Fab")
		)
		(fp_line
			(start 1.27 -3.81)
			(end -1.27 -3.81)
			(stroke
				(width 0.1)
				(type default)
			)
			(layer "F.Fab")
		)
		(fp_line
			(start 1.27 3.81)
			(end 1.27 -3.81)
			(stroke
				(width 0.1)
				(type default)
			)
			(layer "F.Fab")
		)
		(fp_poly
			(pts
				(xy 4.3942 -3.048) (xy 4.3942 -2.032) (xy 3.3782 -2.54)
			)
			(stroke
				(width 0)
				(type default)
			)
			(fill yes)
			(layer "F.Fab")
		)
		(fp_text user "3"
			(at 3.921252 2.54 90)
			(unlocked yes)
			(layer "F.SilkS")
			(effects
				(font
					(size 0.7874 0.5842)
					(thickness 0.1524)
				)
			)
		)
		(fp_text user "3"
			(at 3.921252 2.54 90)
			(unlocked yes)
			(layer "F.Fab")
			(effects
				(font
					(size 0.7874 0.5842)
					(thickness 0.1524)
				)
			)
		)
		(pad "1" smd rect
			(at 1.459992 -2.54 90)
			(size 1.27 3.429)
			(layers "F.Cu" "F.Mask" "F.Paste")
			(net "GND")
		)
		(pad "2" smd rect
			(at -1.459992 0 90)
			(size 1.27 3.429)
			(layers "F.Cu" "F.Mask" "F.Paste")
			(net "UART_PEX1_SDB_BUF_R1_TX")
		)
		(pad "3" smd rect
			(at 1.459992 2.54 90)
			(size 1.27 3.429)
			(layers "F.Cu" "F.Mask" "F.Paste")
			(net "UART_PEX1_SDB_R1_RX")
		)
	)
)
